(kicad_pcb
	(version 20260206)
	(generator "pcbnew")
	(generator_version "10.0")
	(general
		(thickness 1.6)
		(legacy_teardrops no)
	)
	(paper "A4")
	(title_block
		(title "03242023_DA0F0TMBIJ0_F0T_Motherboard_J_brd_V01_OCP.brd")
		(comment 1 "Grand Teton / footprints 696-703 of 6105")
	)
	(layers
		(0 "F.Cu" signal "TOP")
		(4 "In1.Cu" signal "GND")
		(6 "In2.Cu" signal "IN1")
		(8 "In3.Cu" signal "GND1")
		(10 "In4.Cu" signal "IN2")
		(12 "In5.Cu" signal "GND2")
		(14 "In6.Cu" signal "IN3")
		(16 "In7.Cu" signal "GND3")
		(18 "In8.Cu" signal "VCC")
		(20 "In9.Cu" signal "VCC1")
		(22 "In10.Cu" signal "GND4")
		(24 "In11.Cu" signal "IN4")
		(26 "In12.Cu" signal "GND5")
		(28 "In13.Cu" signal "IN5")
		(30 "In14.Cu" signal "GND6")
		(32 "In15.Cu" signal "IN6")
		(34 "In16.Cu" signal "GND7")
		(2 "B.Cu" signal "BOTTOM")
		(9 "F.Adhes" user "F.Adhesive")
		(11 "B.Adhes" user "B.Adhesive")
		(13 "F.Paste" user "Package Geometry/Pastemask Top")
		(15 "B.Paste" user "Package Geometry/Pastemask Bottom")
		(5 "F.SilkS" user "Ref Des/Silkscreen Top")
		(7 "B.SilkS" user "Ref Des/Silkscreen Bottom")
		(1 "F.Mask" user "Board Geometry/Soldermask Top")
		(3 "B.Mask" user "Board Geometry/Soldermask Bottom")
		(17 "Dwgs.User" user "User.Drawings")
		(19 "Cmts.User" user "User.Comments")
		(21 "Eco1.User" user "User.Eco1")
		(23 "Eco2.User" user "User.Eco2")
		(25 "Edge.Cuts" user "Board Geometry/Outline")
		(27 "Margin" user)
		(31 "F.CrtYd" user "Package Geometry/Place Bound Top")
		(29 "B.CrtYd" user "Package Geometry/Place Bound Bottom")
		(35 "F.Fab" user "Ref Des/Assembly Top")
		(33 "B.Fab" user "Ref Des/Assembly Bottom")
	)
	(footprint ""
		(layer "F.Cu")
		(at 162.848036 -66.091308 180)
		(property "Reference" "R3773"
			(at 0 0 180)
			(layer "F.SilkS")
			(hide yes)
			(effects
				(font
					(size 1.27 1.27)
				)
			)
		)
		(property "Value" ""
			(at 0 0 180)
			(layer "F.Fab")
			(effects
				(font
					(size 1.27 1.27)
				)
			)
		)
		(duplicate_pad_numbers_are_jumpers no)
		(fp_line
			(start 0.7874 0.4064)
			(end -0.7874 0.4064)
			(stroke
				(width 0.1524)
				(type default)
			)
			(layer "F.SilkS")
		)
		(fp_line
			(start 0.7874 -0.4064)
			(end 0.7874 0.4064)
			(stroke
				(width 0.1524)
				(type default)
			)
			(layer "F.SilkS")
		)
		(fp_line
			(start -0.7874 0.4064)
			(end -0.7874 -0.4064)
			(stroke
				(width 0.1524)
				(type default)
			)
			(layer "F.SilkS")
		)
		(fp_line
			(start -0.7874 -0.4064)
			(end 0.7874 -0.4064)
			(stroke
				(width 0.1524)
				(type default)
			)
			(layer "F.SilkS")
		)
		(fp_line
			(start 0.67945 0.3048)
			(end 0.120396 0.3048)
			(stroke
				(width 0.1)
				(type default)
			)
			(layer "F.Fab")
		)
		(fp_line
			(start 0.67945 -0.3048)
			(end 0.67945 0.3048)
			(stroke
				(width 0.1)
				(type default)
			)
			(layer "F.Fab")
		)
		(fp_line
			(start 0.12065 -0.2794)
			(end 0.12065 -0.3048)
			(stroke
				(width 0.1)
				(type default)
			)
			(layer "F.Fab")
		)
		(fp_line
			(start 0.12065 -0.3048)
			(end 0.67945 -0.3048)
			(stroke
				(width 0.1)
				(type default)
			)
			(layer "F.Fab")
		)
		(fp_line
			(start 0.120396 0.3048)
			(end 0.120396 0.2794)
			(stroke
				(width 0.1)
				(type default)
			)
			(layer "F.Fab")
		)
		(fp_line
			(start 0.120396 0.2794)
			(end -0.12065 0.2794)
			(stroke
				(width 0.1)
				(type default)
			)
			(layer "F.Fab")
		)
		(fp_line
			(start -0.12065 0.3048)
			(end -0.67945 0.3048)
			(stroke
				(width 0.1)
				(type default)
			)
			(layer "F.Fab")
		)
		(fp_line
			(start -0.12065 0.2794)
			(end -0.12065 0.3048)
			(stroke
				(width 0.1)
				(type default)
			)
			(layer "F.Fab")
		)
		(fp_line
			(start -0.12065 -0.2794)
			(end 0.12065 -0.2794)
			(stroke
				(width 0.1)
				(type default)
			)
			(layer "F.Fab")
		)
		(fp_line
			(start -0.12065 -0.305054)
			(end -0.12065 -0.2794)
			(stroke
				(width 0.1)
				(type default)
			)
			(layer "F.Fab")
		)
		(fp_line
			(start -0.67945 0.3048)
			(end -0.67945 -0.305054)
			(stroke
				(width 0.1)
				(type default)
			)
			(layer "F.Fab")
		)
		(fp_line
			(start -0.67945 -0.305054)
			(end -0.12065 -0.305054)
			(stroke
				(width 0.1)
				(type default)
			)
			(layer "F.Fab")
		)
		(pad "1" smd circle
			(at -0.40005 0 180)
			(size 0 0)
			(layers "F.Cu" "F.Mask" "F.Paste")
			(net "P3V3_AUX")
		)
		(pad "2" smd circle
			(at 0.40005 0 180)
			(size 0 0)
			(layers "F.Cu" "F.Mask" "F.Paste")
			(net "RST_SMB_E1S_0_N")
		)
	)
	(footprint ""
		(layer "F.Cu")
		(at 96.57588 -55.209948 180)
		(property "Reference" "C1293"
			(at 0 0 180)
			(layer "F.SilkS")
			(hide yes)
			(effects
				(font
					(size 1.27 1.27)
				)
			)
		)
		(property "Value" ""
			(at 0 0 180)
			(layer "F.Fab")
			(effects
				(font
					(size 1.27 1.27)
				)
			)
		)
		(duplicate_pad_numbers_are_jumpers no)
		(fp_line
			(start 0.7874 0.4064)
			(end -0.7874 0.4064)
			(stroke
				(width 0.1524)
				(type default)
			)
			(layer "F.SilkS")
		)
		(fp_line
			(start 0.7874 -0.4064)
			(end 0.7874 0.4064)
			(stroke
				(width 0.1524)
				(type default)
			)
			(layer "F.SilkS")
		)
		(fp_line
			(start -0.7874 0.4064)
			(end -0.7874 -0.4064)
			(stroke
				(width 0.1524)
				(type default)
			)
			(layer "F.SilkS")
		)
		(fp_line
			(start -0.7874 -0.4064)
			(end 0.7874 -0.4064)
			(stroke
				(width 0.1524)
				(type default)
			)
			(layer "F.SilkS")
		)
		(fp_line
			(start 0.67945 0.3048)
			(end 0.120396 0.3048)
			(stroke
				(width 0.1)
				(type default)
			)
			(layer "F.Fab")
		)
		(fp_line
			(start 0.67945 -0.3048)
			(end 0.67945 0.3048)
			(stroke
				(width 0.1)
				(type default)
			)
			(layer "F.Fab")
		)
		(fp_line
			(start 0.12065 -0.2794)
			(end 0.12065 -0.3048)
			(stroke
				(width 0.1)
				(type default)
			)
			(layer "F.Fab")
		)
		(fp_line
			(start 0.12065 -0.3048)
			(end 0.67945 -0.3048)
			(stroke
				(width 0.1)
				(type default)
			)
			(layer "F.Fab")
		)
		(fp_line
			(start 0.120396 0.3048)
			(end 0.120396 0.2794)
			(stroke
				(width 0.1)
				(type default)
			)
			(layer "F.Fab")
		)
		(fp_line
			(start 0.120396 0.2794)
			(end -0.12065 0.2794)
			(stroke
				(width 0.1)
				(type default)
			)
			(layer "F.Fab")
		)
		(fp_line
			(start -0.12065 0.3048)
			(end -0.67945 0.3048)
			(stroke
				(width 0.1)
				(type default)
			)
			(layer "F.Fab")
		)
		(fp_line
			(start -0.12065 0.2794)
			(end -0.12065 0.3048)
			(stroke
				(width 0.1)
				(type default)
			)
			(layer "F.Fab")
		)
		(fp_line
			(start -0.12065 -0.2794)
			(end 0.12065 -0.2794)
			(stroke
				(width 0.1)
				(type default)
			)
			(layer "F.Fab")
		)
		(fp_line
			(start -0.12065 -0.305054)
			(end -0.12065 -0.2794)
			(stroke
				(width 0.1)
				(type default)
			)
			(layer "F.Fab")
		)
		(fp_line
			(start -0.67945 0.3048)
			(end -0.67945 -0.305054)
			(stroke
				(width 0.1)
				(type default)
			)
			(layer "F.Fab")
		)
		(fp_line
			(start -0.67945 -0.305054)
			(end -0.12065 -0.305054)
			(stroke
				(width 0.1)
				(type default)
			)
			(layer "F.Fab")
		)
		(pad "1" smd circle
			(at -0.40005 0 180)
			(size 0 0)
			(layers "F.Cu" "F.Mask" "F.Paste")
			(net "FM_BMC_EN_DET")
		)
		(pad "2" smd circle
			(at 0.40005 0 180)
			(size 0 0)
			(layers "F.Cu" "F.Mask" "F.Paste")
			(net "GND")
		)
	)
	(footprint ""
		(layer "F.Cu")
		(at 409.07081 -402.371052 -90)
		(property "Reference" "C958"
			(at 0 0 270)
			(layer "F.SilkS")
			(hide yes)
			(effects
				(font
					(size 1.27 1.27)
				)
			)
		)
		(property "Value" ""
			(at 0 0 270)
			(layer "F.Fab")
			(effects
				(font
					(size 1.27 1.27)
				)
			)
		)
		(duplicate_pad_numbers_are_jumpers no)
		(fp_line
			(start -0.299974 0.150114)
			(end -0.299974 -0.150114)
			(stroke
				(width 0.1)
				(type default)
			)
			(layer "F.Fab")
		)
		(fp_line
			(start 0.299974 0.150114)
			(end -0.299974 0.150114)
			(stroke
				(width 0.1)
				(type default)
			)
			(layer "F.Fab")
		)
		(fp_line
			(start -0.299974 -0.150114)
			(end 0.299974 -0.150114)
			(stroke
				(width 0.1)
				(type default)
			)
			(layer "F.Fab")
		)
		(fp_line
			(start 0.299974 -0.150114)
			(end 0.299974 0.150114)
			(stroke
				(width 0.1)
				(type default)
			)
			(layer "F.Fab")
		)
		(pad "1" smd rect
			(at -0.2667 0 270)
			(size 0.3048 0.381)
			(layers "F.Cu" "F.Mask" "F.Paste")
			(net "P5E_CPU0_PE2_TX_C_DN<3>")
		)
		(pad "2" smd rect
			(at 0.2667 0 270)
			(size 0.3048 0.381)
			(layers "F.Cu" "F.Mask" "F.Paste")
			(net "P5E_CPU0_PE2_TX_DN<3>")
		)
	)
	(footprint ""
		(layer "F.Cu")
		(at 133.725412 -368.24793)
		(property "Reference" "PC1771"
			(at 0 0 0)
			(layer "F.SilkS")
			(hide yes)
			(effects
				(font
					(size 1.27 1.27)
				)
			)
		)
		(property "Value" ""
			(at 0 0 0)
			(layer "F.Fab")
			(effects
				(font
					(size 1.27 1.27)
				)
			)
		)
		(duplicate_pad_numbers_are_jumpers no)
		(fp_line
			(start -3.400044 1.249934)
			(end 3.400044 1.249934)
			(stroke
				(width 0.1524)
				(type default)
			)
			(layer "F.SilkS")
		)
		(fp_circle
			(center 0 1.249934)
			(end 3.400044 1.249934)
			(stroke
				(width 0.1524)
				(type default)
			)
			(fill no)
			(layer "F.SilkS")
		)
		(fp_poly
			(pts
				(arc
					(start 3.400044 1.249934)
					(mid 0 4.649978)
					(end -3.400044 1.249934)
				)
			)
			(stroke
				(width 0)
				(type default)
			)
			(fill yes)
			(layer "F.SilkS")
		)
		(fp_circle
			(center 0 1.249934)
			(end 3.400044 1.249934)
			(stroke
				(width 0.1)
				(type default)
			)
			(fill no)
			(layer "F.Fab")
		)
		(pad "1" thru_hole rect
			(at 0 0)
			(size 1.524 1.524)
			(drill 1.016)
			(layers "*.Cu" "*.Mask")
			(remove_unused_layers no)
			(net "PVPP_HBM_CPU1")
			(clearance 0)
			(padstack
				(mode front_inner_back)
				(layer "Inner"
					(shape circle)
					(size 1.524 1.524)
					(clearance 0)
				)
				(layer "B.Cu"
					(shape rect)
					(size 1.524 1.524)
					(clearance 0)
				)
			)
		)
		(pad "2" thru_hole circle
			(at 0 2.500122)
			(size 1.524 1.524)
			(drill 1.016)
			(layers "*.Cu" "*.Mask")
			(remove_unused_layers no)
			(net "GND")
			(clearance 0)
		)
	)
	(footprint ""
		(layer "F.Cu")
		(at 90.440002 -297.514772)
		(property "Reference" "H22"
			(at -3.582162 -6.911086 0)
			(unlocked yes)
			(layer "F.SilkS")
			(effects
				(font
					(size 0.7874 0.5842)
					(thickness 0.1524)
				)
				(justify left)
			)
		)
		(property "Value" ""
			(at 0 0 0)
			(layer "F.Fab")
			(effects
				(font
					(size 1.27 1.27)
				)
			)
		)
		(duplicate_pad_numbers_are_jumpers no)
		(fp_circle
			(center 0 0)
			(end 2.5273 0)
			(stroke
				(width 0.1524)
				(type default)
			)
			(fill no)
			(layer "F.SilkS")
		)
		(fp_circle
			(center 0 0)
			(end 2.5273 0)
			(stroke
				(width 0.1524)
				(type default)
			)
			(fill no)
			(layer "B.SilkS")
		)
		(fp_circle
			(center 0 0)
			(end 2.5273 0)
			(stroke
				(width 0.1)
				(type default)
			)
			(fill no)
			(layer "B.Fab")
		)
		(fp_circle
			(center 0 0)
			(end 2.5273 0)
			(stroke
				(width 0.1)
				(type default)
			)
			(fill no)
			(layer "F.Fab")
		)
		(pad "" np_thru_hole circle
			(at 0 0)
			(size 3.429 3.429)
			(drill 3.429)
			(layers "*.Cu" "*.Mask")
			(clearance 0.381)
			(thermal_gap 0.381)
		)
	)
	(footprint ""
		(layer "F.Cu")
		(at 73.81748 -162.003486)
		(property "Reference" "PC379"
			(at 0 0 0)
			(layer "F.SilkS")
			(hide yes)
			(effects
				(font
					(size 1.27 1.27)
				)
			)
		)
		(property "Value" ""
			(at 0 0 0)
			(layer "F.Fab")
			(effects
				(font
					(size 1.27 1.27)
				)
			)
		)
		(duplicate_pad_numbers_are_jumpers no)
		(fp_line
			(start -0.7874 -0.4064)
			(end 0.7874 -0.4064)
			(stroke
				(width 0.1524)
				(type default)
			)
			(layer "F.SilkS")
		)
		(fp_line
			(start -0.7874 0.4064)
			(end -0.7874 -0.4064)
			(stroke
				(width 0.1524)
				(type default)
			)
			(layer "F.SilkS")
		)
		(fp_line
			(start 0.7874 -0.4064)
			(end 0.7874 0.4064)
			(stroke
				(width 0.1524)
				(type default)
			)
			(layer "F.SilkS")
		)
		(fp_line
			(start 0.7874 0.4064)
			(end -0.7874 0.4064)
			(stroke
				(width 0.1524)
				(type default)
			)
			(layer "F.SilkS")
		)
		(fp_line
			(start -0.67945 -0.305054)
			(end -0.12065 -0.305054)
			(stroke
				(width 0.1)
				(type default)
			)
			(layer "F.Fab")
		)
		(fp_line
			(start -0.67945 0.3048)
			(end -0.67945 -0.305054)
			(stroke
				(width 0.1)
				(type default)
			)
			(layer "F.Fab")
		)
		(fp_line
			(start -0.12065 -0.305054)
			(end -0.12065 -0.2794)
			(stroke
				(width 0.1)
				(type default)
			)
			(layer "F.Fab")
		)
		(fp_line
			(start -0.12065 -0.2794)
			(end 0.12065 -0.2794)
			(stroke
				(width 0.1)
				(type default)
			)
			(layer "F.Fab")
		)
		(fp_line
			(start -0.12065 0.2794)
			(end -0.12065 0.3048)
			(stroke
				(width 0.1)
				(type default)
			)
			(layer "F.Fab")
		)
		(fp_line
			(start -0.12065 0.3048)
			(end -0.67945 0.3048)
			(stroke
				(width 0.1)
				(type default)
			)
			(layer "F.Fab")
		)
		(fp_line
			(start 0.120396 0.2794)
			(end -0.12065 0.2794)
			(stroke
				(width 0.1)
				(type default)
			)
			(layer "F.Fab")
		)
		(fp_line
			(start 0.120396 0.3048)
			(end 0.120396 0.2794)
			(stroke
				(width 0.1)
				(type default)
			)
			(layer "F.Fab")
		)
		(fp_line
			(start 0.12065 -0.3048)
			(end 0.67945 -0.3048)
			(stroke
				(width 0.1)
				(type default)
			)
			(layer "F.Fab")
		)
		(fp_line
			(start 0.12065 -0.2794)
			(end 0.12065 -0.3048)
			(stroke
				(width 0.1)
				(type default)
			)
			(layer "F.Fab")
		)
		(fp_line
			(start 0.67945 -0.3048)
			(end 0.67945 0.3048)
			(stroke
				(width 0.1)
				(type default)
			)
			(layer "F.Fab")
		)
		(fp_line
			(start 0.67945 0.3048)
			(end 0.120396 0.3048)
			(stroke
				(width 0.1)
				(type default)
			)
			(layer "F.Fab")
		)
		(pad "1" smd circle
			(at -0.40005 0)
			(size 0 0)
			(layers "F.Cu" "F.Mask" "F.Paste")
			(net "PVCCD_HV_CPU1")
		)
		(pad "2" smd circle
			(at 0.40005 0)
			(size 0 0)
			(layers "F.Cu" "F.Mask" "F.Paste")
			(net "GND")
		)
	)
	(footprint ""
		(layer "F.Cu")
		(at 306.63388 -53.050948 90)
		(property "Reference" "R146"
			(at 0 0 90)
			(layer "F.SilkS")
			(hide yes)
			(effects
				(font
					(size 1.27 1.27)
				)
			)
		)
		(property "Value" ""
			(at 0 0 90)
			(layer "F.Fab")
			(effects
				(font
					(size 1.27 1.27)
				)
			)
		)
		(duplicate_pad_numbers_are_jumpers no)
		(fp_line
			(start 0.7874 -0.4064)
			(end 0.7874 0.4064)
			(stroke
				(width 0.1524)
				(type default)
			)
			(layer "F.SilkS")
		)
		(fp_line
			(start -0.7874 -0.4064)
			(end 0.7874 -0.4064)
			(stroke
				(width 0.1524)
				(type default)
			)
			(layer "F.SilkS")
		)
		(fp_line
			(start 0.7874 0.4064)
			(end -0.7874 0.4064)
			(stroke
				(width 0.1524)
				(type default)
			)
			(layer "F.SilkS")
		)
		(fp_line
			(start -0.7874 0.4064)
			(end -0.7874 -0.4064)
			(stroke
				(width 0.1524)
				(type default)
			)
			(layer "F.SilkS")
		)
		(fp_line
			(start -0.12065 -0.305054)
			(end -0.12065 -0.2794)
			(stroke
				(width 0.1)
				(type default)
			)
			(layer "F.Fab")
		)
		(fp_line
			(start -0.67945 -0.305054)
			(end -0.12065 -0.305054)
			(stroke
				(width 0.1)
				(type default)
			)
			(layer "F.Fab")
		)
		(fp_line
			(start 0.67945 -0.3048)
			(end 0.67945 0.3048)
			(stroke
				(width 0.1)
				(type default)
			)
			(layer "F.Fab")
		)
		(fp_line
			(start 0.12065 -0.3048)
			(end 0.67945 -0.3048)
			(stroke
				(width 0.1)
				(type default)
			)
			(layer "F.Fab")
		)
		(fp_line
			(start 0.12065 -0.2794)
			(end 0.12065 -0.3048)
			(stroke
				(width 0.1)
				(type default)
			)
			(layer "F.Fab")
		)
		(fp_line
			(start -0.12065 -0.2794)
			(end 0.12065 -0.2794)
			(stroke
				(width 0.1)
				(type default)
			)
			(layer "F.Fab")
		)
		(fp_line
			(start 0.120396 0.2794)
			(end -0.12065 0.2794)
			(stroke
				(width 0.1)
				(type default)
			)
			(layer "F.Fab")
		)
		(fp_line
			(start -0.12065 0.2794)
			(end -0.12065 0.3048)
			(stroke
				(width 0.1)
				(type default)
			)
			(layer "F.Fab")
		)
		(fp_line
			(start 0.67945 0.3048)
			(end 0.120396 0.3048)
			(stroke
				(width 0.1)
				(type default)
			)
			(layer "F.Fab")
		)
		(fp_line
			(start 0.120396 0.3048)
			(end 0.120396 0.2794)
			(stroke
				(width 0.1)
				(type default)
			)
			(layer "F.Fab")
		)
		(fp_line
			(start -0.12065 0.3048)
			(end -0.67945 0.3048)
			(stroke
				(width 0.1)
				(type default)
			)
			(layer "F.Fab")
		)
		(fp_line
			(start -0.67945 0.3048)
			(end -0.67945 -0.305054)
			(stroke
				(width 0.1)
				(type default)
			)
			(layer "F.Fab")
		)
		(pad "1" smd circle
			(at -0.40005 0 90)
			(size 0 0)
			(layers "F.Cu" "F.Mask" "F.Paste")
			(net "PVNN_TERM_CPU0")
		)
		(pad "2" smd circle
			(at 0.40005 0 90)
			(size 0 0)
			(layers "F.Cu" "F.Mask" "F.Paste")
			(net "PECI_BMC_R")
		)
	)
	(footprint ""
		(layer "F.Cu")
		(at 209.74558 -129.814828 180)
		(property "Reference" "R1950"
			(at 0 0 180)
			(layer "F.SilkS")
			(hide yes)
			(effects
				(font
					(size 1.27 1.27)
				)
			)
		)
		(property "Value" ""
			(at 0 0 180)
			(layer "F.Fab")
			(effects
				(font
					(size 1.27 1.27)
				)
			)
		)
		(duplicate_pad_numbers_are_jumpers no)
		(fp_line
			(start 0.7874 0.4064)
			(end -0.7874 0.4064)
			(stroke
				(width 0.1524)
				(type default)
			)
			(layer "F.SilkS")
		)
		(fp_line
			(start 0.7874 -0.4064)
			(end 0.7874 0.4064)
			(stroke
				(width 0.1524)
				(type default)
			)
			(layer "F.SilkS")
		)
		(fp_line
			(start -0.7874 0.4064)
			(end -0.7874 -0.4064)
			(stroke
				(width 0.1524)
				(type default)
			)
			(layer "F.SilkS")
		)
		(fp_line
			(start -0.7874 -0.4064)
			(end 0.7874 -0.4064)
			(stroke
				(width 0.1524)
				(type default)
			)
			(layer "F.SilkS")
		)
		(fp_line
			(start 0.67945 0.3048)
			(end 0.120396 0.3048)
			(stroke
				(width 0.1)
				(type default)
			)
			(layer "F.Fab")
		)
		(fp_line
			(start 0.67945 -0.3048)
			(end 0.67945 0.3048)
			(stroke
				(width 0.1)
				(type default)
			)
			(layer "F.Fab")
		)
		(fp_line
			(start 0.12065 -0.2794)
			(end 0.12065 -0.3048)
			(stroke
				(width 0.1)
				(type default)
			)
			(layer "F.Fab")
		)
		(fp_line
			(start 0.12065 -0.3048)
			(end 0.67945 -0.3048)
			(stroke
				(width 0.1)
				(type default)
			)
			(layer "F.Fab")
		)
		(fp_line
			(start 0.120396 0.3048)
			(end 0.120396 0.2794)
			(stroke
				(width 0.1)
				(type default)
			)
			(layer "F.Fab")
		)
		(fp_line
			(start 0.120396 0.2794)
			(end -0.12065 0.2794)
			(stroke
				(width 0.1)
				(type default)
			)
			(layer "F.Fab")
		)
		(fp_line
			(start -0.12065 0.3048)
			(end -0.67945 0.3048)
			(stroke
				(width 0.1)
				(type default)
			)
			(layer "F.Fab")
		)
		(fp_line
			(start -0.12065 0.2794)
			(end -0.12065 0.3048)
			(stroke
				(width 0.1)
				(type default)
			)
			(layer "F.Fab")
		)
		(fp_line
			(start -0.12065 -0.2794)
			(end 0.12065 -0.2794)
			(stroke
				(width 0.1)
				(type default)
			)
			(layer "F.Fab")
		)
		(fp_line
			(start -0.12065 -0.305054)
			(end -0.12065 -0.2794)
			(stroke
				(width 0.1)
				(type default)
			)
			(layer "F.Fab")
		)
		(fp_line
			(start -0.67945 0.3048)
			(end -0.67945 -0.305054)
			(stroke
				(width 0.1)
				(type default)
			)
			(layer "F.Fab")
		)
		(fp_line
			(start -0.67945 -0.305054)
			(end -0.12065 -0.305054)
			(stroke
				(width 0.1)
				(type default)
			)
			(layer "F.Fab")
		)
		(pad "1" smd circle
			(at -0.40005 0 180)
			(size 0 0)
			(layers "F.Cu" "F.Mask" "F.Paste")
			(net "FM_COMP_P3V3_AUX_VIN")
		)
		(pad "2" smd circle
			(at 0.40005 0 180)
			(size 0 0)
			(layers "F.Cu" "F.Mask" "F.Paste")
			(net "FM_COMP_P3V3_AUX_VIN_R")
		)
	)
)
